FILE_TYPE=LIBRARY_PARTS;
primitive '120R2F-GP';
  pin
    '1':
      PIN_NUMBER='(1)';
      PIN_TYPE='ANALOG';
      NO_LOAD_CHECK='Both';
      NO_IO_CHECK='Both';
      NO_ASSERT_CHECK='TRUE';
      NO_DIR_CHECK='TRUE';
      ALLOW_CONNECT='TRUE';
    '2':
      PIN_NUMBER='(2)';
      PIN_TYPE='ANALOG';
      NO_LOAD_CHECK='Both';
      NO_IO_CHECK='Both';
      NO_ASSERT_CHECK='TRUE';
      NO_DIR_CHECK='TRUE';
      ALLOW_CONNECT='TRUE';
  end_pin;
  body
    PART_NAME='120R2F-GP';
    BODY_NAME='120R2F-GP';
    PHYS_DES_PREFIX='R';
    CLASS='DISCRETE';
  end_body;
end_primitive;

END.
